(kicad_pcb
	(version 20241229)
	(generator "pcbnew")
	(generator_version "9.0")
	(general
		(thickness 1.61)
		(legacy_teardrops no)
	)
	(paper "A3")
	(title_block
		(title "RDIMM DDR5 Tester")
		(date "2026-05-21")
		(rev "2.2.0")
		(company "Antmicro")
		(comment 9 "footprints 290-291 of 796")
	)
	(layers
		(0 "F.Cu" signal)
		(4 "In1.Cu" power)
		(6 "In2.Cu" mixed)
		(8 "In3.Cu" power)
		(10 "In4.Cu" mixed)
		(12 "In5.Cu" power)
		(14 "In6.Cu" mixed)
		(16 "In7.Cu" power)
		(18 "In8.Cu" power)
		(20 "In9.Cu" mixed)
		(22 "In10.Cu" power)
		(2 "B.Cu" signal)
		(9 "F.Adhes" user "F.Adhesive")
		(11 "B.Adhes" user "B.Adhesive")
		(13 "F.Paste" user)
		(15 "B.Paste" user)
		(5 "F.SilkS" user "F.Silkscreen")
		(7 "B.SilkS" user "B.Silkscreen")
		(1 "F.Mask" user)
		(3 "B.Mask" user)
		(17 "Dwgs.User" user "User.Drawings")
		(19 "Cmts.User" user "User.Comments")
		(21 "Eco1.User" user "User.Eco1")
		(23 "Eco2.User" user "User.Eco2")
		(25 "Edge.Cuts" user)
		(27 "Margin" user)
		(31 "F.CrtYd" user "F.Courtyard")
		(29 "B.CrtYd" user "B.Courtyard")
		(35 "F.Fab" user)
		(33 "B.Fab" user)
	)
	(footprint "antmicro-footprints:SOD-523"
		(layer "F.Cu")
		(at 108.84 146.96)
		(property "Reference" "D18"
			(at 1.11 0.44 0)
			(layer "F.SilkS")
			(effects
				(font
					(size 0.7 0.7)
					(thickness 0.15)
				)
				(justify left bottom)
			)
		)
		(property "Value" "PESD5V0X1UB"
			(at 0 1.499 0)
			(layer "F.Fab")
			(effects
				(font
					(size 0.7 0.7)
					(thickness 0.15)
				)
				(justify left bottom)
			)
		)
		(property "Datasheet" "https://assets.nexperia.com/documents/data-sheet/PESD5V0X1UB.pdf"
			(at 0 0 0)
			(layer "F.Fab")
			(hide yes)
			(effects
				(font
					(size 1.27 1.27)
					(thickness 0.15)
				)
			)
		)
		(property "MPN" "PESD5V0X1UB,135"
			(at 0 0 0)
			(unlocked yes)
			(layer "F.Fab")
			(hide yes)
			(effects
				(font
					(size 1 1)
					(thickness 0.15)
				)
			)
		)
		(property "Manufacturer" "Nexperia"
			(at 0 0 0)
			(unlocked yes)
			(layer "F.Fab")
			(hide yes)
			(effects
				(font
					(size 1 1)
					(thickness 0.15)
				)
			)
		)
		(property "Author" "Antmicro"
			(at 0 0 0)
			(unlocked yes)
			(layer "F.Fab")
			(hide yes)
			(effects
				(font
					(size 1 1)
					(thickness 0.15)
				)
			)
		)
		(property "License" "Apache-2.0"
			(at 0 0 0)
			(unlocked yes)
			(layer "F.Fab")
			(hide yes)
			(effects
				(font
					(size 1 1)
					(thickness 0.15)
				)
			)
		)
		(sheetname "/Debug FTDI + VNA/")
		(sheetfile "debug-ftdi.kicad_sch")
		(attr smd)
		(fp_line
			(start -0.35 -0.5)
			(end -0.35 0.5)
			(stroke
				(width 0.15)
				(type solid)
			)
			(layer "F.SilkS")
		)
		(fp_rect
			(start -1 -0.6)
			(end 1 0.6)
			(stroke
				(width 0.05)
				(type solid)
			)
			(fill no)
			(layer "F.CrtYd")
		)
		(fp_line
			(start -0.652 -0.425)
			(end 0.65 -0.425)
			(stroke
				(width 0.15)
				(type solid)
			)
			(layer "F.Fab")
		)
		(fp_line
			(start -0.652 0.423)
			(end -0.652 -0.425)
			(stroke
				(width 0.15)
				(type solid)
			)
			(layer "F.Fab")
		)
		(fp_line
			(start -0.652 0.423)
			(end 0.65 0.423)
			(stroke
				(width 0.15)
				(type solid)
			)
			(layer "F.Fab")
		)
		(fp_line
			(start -0.35 -0.4)
			(end -0.35 0.4)
			(stroke
				(width 0.15)
				(type solid)
			)
			(layer "F.Fab")
		)
		(fp_line
			(start 0.65 -0.425)
			(end 0.65 0.423)
			(stroke
				(width 0.15)
				(type solid)
			)
			(layer "F.Fab")
		)
		(fp_text user "Author: Antmicro"
			(at -1.276 4.7 0)
			(layer "F.Fab")
			(effects
				(font
					(size 0.7 0.7)
					(thickness 0.15)
				)
				(justify left bottom)
			)
		)
		(fp_text user "License: Apache-2.0"
			(at -1.276 5.9 0)
			(layer "F.Fab")
			(effects
				(font
					(size 0.7 0.7)
					(thickness 0.15)
				)
				(justify left bottom)
			)
		)
		(fp_text user "${REFERENCE}"
			(at -1.276 3.499 0)
			(layer "F.Fab")
			(effects
				(font
					(size 0.7 0.7)
					(thickness 0.15)
				)
				(justify left bottom)
			)
		)
		(pad "1" smd roundrect
			(at -0.701 0)
			(size 0.5 0.6)
			(layers "F.Cu" "F.Mask" "F.Paste")
			(roundrect_rratio 0.25)
			(net 2 "/Debug FTDI + VNA/VBUS")
			(pinfunction "C")
			(pintype "passive")
		)
		(pad "2" smd roundrect
			(at 0.699 0)
			(size 0.5 0.6)
			(layers "F.Cu" "F.Mask" "F.Paste")
			(roundrect_rratio 0.25)
			(net 1 "GND")
			(pinfunction "A")
			(pintype "passive")
		)
	)
	(footprint "antmicro-footprints:NetTie-2_SMD_Pad0.127mm"
		(layer "F.Cu")
		(at 246.887 150.451)
		(descr "Net tie, 2 pin, 0.127mm  SMD pads")
		(tags "net tie")
		(property "Reference" "NT6"
			(at -0.128 -1.345 0)
			(layer "F.SilkS")
			(hide yes)
			(effects
				(font
					(size 0.7 0.7)
					(thickness 0.15)
				)
				(justify left bottom)
			)
		)
		(property "Value" "Net-Tie_P0.127mm"
			(at 0 1.199 0)
			(layer "F.Fab")
			(effects
				(font
					(size 0.7 0.7)
					(thickness 0.15)
				)
				(justify left bottom)
			)
		)
		(property "MPN" ""
			(at 0 0 0)
			(unlocked yes)
			(layer "F.Fab")
			(hide yes)
			(effects
				(font
					(size 1 1)
					(thickness 0.15)
				)
			)
		)
		(property "Manufacturer" ""
			(at 0 0 0)
			(unlocked yes)
			(layer "F.Fab")
			(hide yes)
			(effects
				(font
					(size 1 1)
					(thickness 0.15)
				)
			)
		)
		(property "Author" "Antmicro"
			(at 0 0 0)
			(unlocked yes)
			(layer "F.Fab")
			(hide yes)
			(effects
				(font
					(size 1 1)
					(thickness 0.15)
				)
			)
		)
		(property "License" "Apache-2.0"
			(at 0 0 0)
			(unlocked yes)
			(layer "F.Fab")
			(hide yes)
			(effects
				(font
					(size 1 1)
					(thickness 0.15)
				)
			)
		)
		(property ki_fp_filters "Net*Tie*")
		(sheetname "/Supply/DC-DC IO/")
		(sheetfile "dc-dc-io.kicad_sch")
		(attr through_hole exclude_from_pos_files exclude_from_bom)
		(net_tie_pad_groups "1, 2")
		(fp_poly
			(pts
				(xy -0.0635 -0.0635) (xy 0.0625 -0.0635) (xy 0.0625 0.0635) (xy -0.0635 0.0635)
			)
			(stroke
				(width 0)
				(type solid)
			)
			(fill yes)
			(layer "F.Cu")
		)
		(fp_poly
			(pts
				(xy 0.2 -0.16) (xy 0.29 -0.07) (xy 0.29 0.07) (xy 0.2 0.16) (xy -0.2 0.16) (xy -0.29 0.07) (xy -0.29 -0.06)
				(xy -0.19 -0.16)
			)
			(stroke
				(width 0.05)
				(type solid)
			)
			(fill no)
			(layer "F.CrtYd")
		)
		(fp_text user "Author: Antmicro"
			(at -0.128 4.4 0)
			(layer "F.Fab")
			(effects
				(font
					(size 0.7 0.7)
					(thickness 0.15)
				)
				(justify left bottom)
			)
		)
		(fp_text user "License: Apache-2.0"
			(at -0.128 5.6 0)
			(layer "F.Fab")
			(effects
				(font
					(size 0.7 0.7)
					(thickness 0.15)
				)
				(justify left bottom)
			)
		)
		(fp_text user "${REFERENCE}"
			(at -0.128 3.2 0)
			(layer "F.Fab")
			(effects
				(font
					(size 0.7 0.7)
					(thickness 0.15)
				)
				(justify left bottom)
			)
		)
		(pad "1" smd roundrect
			(at -0.127 0 180)
			(size 0.127 0.127)
			(layers "F.Cu")
			(roundrect_rratio 0.5)
			(chamfer_ratio 0)
			(chamfer top_left bottom_left)
			(net 686 "/Supply/DC-DC IO/5V_SEN_+")
			(pinfunction "1")
			(pintype "passive")
		)
		(pad "2" smd roundrect
			(at 0.126 0)
			(size 0.127 0.127)
			(layers "F.Cu")
			(roundrect_rratio 0.5)
			(chamfer_ratio 0)
			(chamfer top_left bottom_left)
			(net 46 "/Supply/DC-DC IO/5V_local")
			(pinfunction "2")
			(pintype "passive")
		)
	)
)
